(kicad_pcb
	(version 20260206)
	(generator "pcbnew")
	(generator_version "10.0")
	(general
		(thickness 1.6)
		(legacy_teardrops no)
	)
	(paper "A4")
	(title_block
		(title "04192023_DAF0TMB3IC0_F0TG_MB_C_brd_V02_OCP.brd")
		(comment 1 "Grand Teton / footprints 1409-1416 of 8354")
	)
	(layers
		(0 "F.Cu" signal "TOP")
		(4 "In1.Cu" signal "GND")
		(6 "In2.Cu" signal "IN1")
		(8 "In3.Cu" signal "GND1")
		(10 "In4.Cu" signal "IN2")
		(12 "In5.Cu" signal "GND2")
		(14 "In6.Cu" signal "IN3")
		(16 "In7.Cu" signal "GND3")
		(18 "In8.Cu" signal "VCC")
		(20 "In9.Cu" signal "VCC1")
		(22 "In10.Cu" signal "GND4")
		(24 "In11.Cu" signal "IN4")
		(26 "In12.Cu" signal "GND5")
		(28 "In13.Cu" signal "IN5")
		(30 "In14.Cu" signal "GND6")
		(32 "In15.Cu" signal "IN6")
		(34 "In16.Cu" signal "GND7")
		(2 "B.Cu" signal "BOTTOM")
		(9 "F.Adhes" user "F.Adhesive")
		(11 "B.Adhes" user "B.Adhesive")
		(13 "F.Paste" user "Package Geometry/Pastemask Top")
		(15 "B.Paste" user "Package Geometry/Pastemask Bottom")
		(5 "F.SilkS" user "Ref Des/Silkscreen Top")
		(7 "B.SilkS" user "Ref Des/Silkscreen Bottom")
		(1 "F.Mask" user "Board Geometry/Soldermask Top")
		(3 "B.Mask" user "Board Geometry/Soldermask Bottom")
		(17 "Dwgs.User" user "User.Drawings")
		(19 "Cmts.User" user "User.Comments")
		(21 "Eco1.User" user "User.Eco1")
		(23 "Eco2.User" user "User.Eco2")
		(25 "Edge.Cuts" user "Board Geometry/Outline")
		(27 "Margin" user)
		(31 "F.CrtYd" user "Package Geometry/Place Bound Top")
		(29 "B.CrtYd" user "Package Geometry/Place Bound Bottom")
		(35 "F.Fab" user "Ref Des/Assembly Top")
		(33 "B.Fab" user "Ref Des/Assembly Bottom")
	)
	(footprint ""
		(layer "F.Cu")
		(at 150.31974 -101.672898)
		(property "Reference" "R3294"
			(at 0 0 0)
			(layer "F.SilkS")
			(hide yes)
			(effects
				(font
					(size 1.27 1.27)
				)
			)
		)
		(property "Value" ""
			(at 0 0 0)
			(layer "F.Fab")
			(effects
				(font
					(size 1.27 1.27)
				)
			)
		)
		(duplicate_pad_numbers_are_jumpers no)
		(fp_line
			(start -0.7874 -0.4064)
			(end 0.7874 -0.4064)
			(stroke
				(width 0.1524)
				(type default)
			)
			(layer "F.SilkS")
		)
		(fp_line
			(start -0.7874 0.4064)
			(end -0.7874 -0.4064)
			(stroke
				(width 0.1524)
				(type default)
			)
			(layer "F.SilkS")
		)
		(fp_line
			(start 0.7874 -0.4064)
			(end 0.7874 0.4064)
			(stroke
				(width 0.1524)
				(type default)
			)
			(layer "F.SilkS")
		)
		(fp_line
			(start 0.7874 0.4064)
			(end -0.7874 0.4064)
			(stroke
				(width 0.1524)
				(type default)
			)
			(layer "F.SilkS")
		)
		(fp_line
			(start -0.67945 -0.305054)
			(end -0.12065 -0.305054)
			(stroke
				(width 0.1)
				(type default)
			)
			(layer "F.Fab")
		)
		(fp_line
			(start -0.67945 0.3048)
			(end -0.67945 -0.305054)
			(stroke
				(width 0.1)
				(type default)
			)
			(layer "F.Fab")
		)
		(fp_line
			(start -0.12065 -0.305054)
			(end -0.12065 -0.2794)
			(stroke
				(width 0.1)
				(type default)
			)
			(layer "F.Fab")
		)
		(fp_line
			(start -0.12065 -0.2794)
			(end 0.12065 -0.2794)
			(stroke
				(width 0.1)
				(type default)
			)
			(layer "F.Fab")
		)
		(fp_line
			(start -0.12065 0.2794)
			(end -0.12065 0.3048)
			(stroke
				(width 0.1)
				(type default)
			)
			(layer "F.Fab")
		)
		(fp_line
			(start -0.12065 0.3048)
			(end -0.67945 0.3048)
			(stroke
				(width 0.1)
				(type default)
			)
			(layer "F.Fab")
		)
		(fp_line
			(start 0.120396 0.2794)
			(end -0.12065 0.2794)
			(stroke
				(width 0.1)
				(type default)
			)
			(layer "F.Fab")
		)
		(fp_line
			(start 0.120396 0.3048)
			(end 0.120396 0.2794)
			(stroke
				(width 0.1)
				(type default)
			)
			(layer "F.Fab")
		)
		(fp_line
			(start 0.12065 -0.3048)
			(end 0.67945 -0.3048)
			(stroke
				(width 0.1)
				(type default)
			)
			(layer "F.Fab")
		)
		(fp_line
			(start 0.12065 -0.2794)
			(end 0.12065 -0.3048)
			(stroke
				(width 0.1)
				(type default)
			)
			(layer "F.Fab")
		)
		(fp_line
			(start 0.67945 -0.3048)
			(end 0.67945 0.3048)
			(stroke
				(width 0.1)
				(type default)
			)
			(layer "F.Fab")
		)
		(fp_line
			(start 0.67945 0.3048)
			(end 0.120396 0.3048)
			(stroke
				(width 0.1)
				(type default)
			)
			(layer "F.Fab")
		)
		(pad "1" smd circle
			(at -0.40005 0)
			(size 0 0)
			(layers "F.Cu" "F.Mask" "F.Paste")
			(net "LED_M2_SSD_0_ACT_N")
		)
		(pad "2" smd circle
			(at 0.40005 0)
			(size 0 0)
			(layers "F.Cu" "F.Mask" "F.Paste")
			(net "LED_HDD_ACTIVITY_N")
		)
	)
	(footprint ""
		(layer "F.Cu")
		(at 302.241458 -113.843308 180)
		(property "Reference" "R69"
			(at 0 0 180)
			(layer "F.SilkS")
			(hide yes)
			(effects
				(font
					(size 1.27 1.27)
				)
			)
		)
		(property "Value" ""
			(at 0 0 180)
			(layer "F.Fab")
			(effects
				(font
					(size 1.27 1.27)
				)
			)
		)
		(duplicate_pad_numbers_are_jumpers no)
		(fp_line
			(start 0.7874 0.4064)
			(end -0.7874 0.4064)
			(stroke
				(width 0.1524)
				(type default)
			)
			(layer "F.SilkS")
		)
		(fp_line
			(start 0.7874 -0.4064)
			(end 0.7874 0.4064)
			(stroke
				(width 0.1524)
				(type default)
			)
			(layer "F.SilkS")
		)
		(fp_line
			(start -0.7874 0.4064)
			(end -0.7874 -0.4064)
			(stroke
				(width 0.1524)
				(type default)
			)
			(layer "F.SilkS")
		)
		(fp_line
			(start -0.7874 -0.4064)
			(end 0.7874 -0.4064)
			(stroke
				(width 0.1524)
				(type default)
			)
			(layer "F.SilkS")
		)
		(fp_line
			(start 0.67945 0.3048)
			(end 0.120396 0.3048)
			(stroke
				(width 0.1)
				(type default)
			)
			(layer "F.Fab")
		)
		(fp_line
			(start 0.67945 -0.3048)
			(end 0.67945 0.3048)
			(stroke
				(width 0.1)
				(type default)
			)
			(layer "F.Fab")
		)
		(fp_line
			(start 0.12065 -0.2794)
			(end 0.12065 -0.3048)
			(stroke
				(width 0.1)
				(type default)
			)
			(layer "F.Fab")
		)
		(fp_line
			(start 0.12065 -0.3048)
			(end 0.67945 -0.3048)
			(stroke
				(width 0.1)
				(type default)
			)
			(layer "F.Fab")
		)
		(fp_line
			(start 0.120396 0.3048)
			(end 0.120396 0.2794)
			(stroke
				(width 0.1)
				(type default)
			)
			(layer "F.Fab")
		)
		(fp_line
			(start 0.120396 0.2794)
			(end -0.12065 0.2794)
			(stroke
				(width 0.1)
				(type default)
			)
			(layer "F.Fab")
		)
		(fp_line
			(start -0.12065 0.3048)
			(end -0.67945 0.3048)
			(stroke
				(width 0.1)
				(type default)
			)
			(layer "F.Fab")
		)
		(fp_line
			(start -0.12065 0.2794)
			(end -0.12065 0.3048)
			(stroke
				(width 0.1)
				(type default)
			)
			(layer "F.Fab")
		)
		(fp_line
			(start -0.12065 -0.2794)
			(end 0.12065 -0.2794)
			(stroke
				(width 0.1)
				(type default)
			)
			(layer "F.Fab")
		)
		(fp_line
			(start -0.12065 -0.305054)
			(end -0.12065 -0.2794)
			(stroke
				(width 0.1)
				(type default)
			)
			(layer "F.Fab")
		)
		(fp_line
			(start -0.67945 0.3048)
			(end -0.67945 -0.305054)
			(stroke
				(width 0.1)
				(type default)
			)
			(layer "F.Fab")
		)
		(fp_line
			(start -0.67945 -0.305054)
			(end -0.12065 -0.305054)
			(stroke
				(width 0.1)
				(type default)
			)
			(layer "F.Fab")
		)
		(pad "1" smd circle
			(at -0.40005 0 180)
			(size 0 0)
			(layers "F.Cu" "F.Mask" "F.Paste")
			(net "CPU_FRU_ADDR0")
		)
		(pad "2" smd circle
			(at 0.40005 0 180)
			(size 0 0)
			(layers "F.Cu" "F.Mask" "F.Paste")
			(net "GND")
		)
	)
	(footprint ""
		(layer "F.Cu")
		(at 347.747844 -378.95403 -90)
		(property "Reference" "C946"
			(at 0 0 270)
			(layer "F.SilkS")
			(hide yes)
			(effects
				(font
					(size 1.27 1.27)
				)
			)
		)
		(property "Value" ""
			(at 0 0 270)
			(layer "F.Fab")
			(effects
				(font
					(size 1.27 1.27)
				)
			)
		)
		(duplicate_pad_numbers_are_jumpers no)
		(fp_line
			(start -0.299974 0.150114)
			(end -0.299974 -0.150114)
			(stroke
				(width 0.1)
				(type default)
			)
			(layer "F.Fab")
		)
		(fp_line
			(start 0.299974 0.150114)
			(end -0.299974 0.150114)
			(stroke
				(width 0.1)
				(type default)
			)
			(layer "F.Fab")
		)
		(fp_line
			(start -0.299974 -0.150114)
			(end 0.299974 -0.150114)
			(stroke
				(width 0.1)
				(type default)
			)
			(layer "F.Fab")
		)
		(fp_line
			(start 0.299974 -0.150114)
			(end 0.299974 0.150114)
			(stroke
				(width 0.1)
				(type default)
			)
			(layer "F.Fab")
		)
		(pad "1" smd rect
			(at -0.2667 0 270)
			(size 0.3048 0.381)
			(layers "F.Cu" "F.Mask" "F.Paste")
			(net "P5E_CPU0_P1_TX_C_DN<9>")
		)
		(pad "2" smd rect
			(at 0.2667 0 270)
			(size 0.3048 0.381)
			(layers "F.Cu" "F.Mask" "F.Paste")
			(net "P5E_CPU0_P1_TX_DN<9>")
		)
	)
	(footprint ""
		(layer "F.Cu")
		(at 94.1832 -401.9804 180)
		(property "Reference" "R1437"
			(at 0 0 180)
			(layer "F.SilkS")
			(hide yes)
			(effects
				(font
					(size 1.27 1.27)
				)
			)
		)
		(property "Value" ""
			(at 0 0 180)
			(layer "F.Fab")
			(effects
				(font
					(size 1.27 1.27)
				)
			)
		)
		(duplicate_pad_numbers_are_jumpers no)
		(fp_line
			(start 0.32512 0.175006)
			(end -0.32512 0.175006)
			(stroke
				(width 0.1)
				(type default)
			)
			(layer "F.Fab")
		)
		(fp_line
			(start 0.32512 -0.175006)
			(end 0.32512 0.175006)
			(stroke
				(width 0.1)
				(type default)
			)
			(layer "F.Fab")
		)
		(fp_line
			(start -0.32512 0.175006)
			(end -0.32512 -0.175006)
			(stroke
				(width 0.1)
				(type default)
			)
			(layer "F.Fab")
		)
		(fp_line
			(start -0.32512 -0.175006)
			(end 0.32512 -0.175006)
			(stroke
				(width 0.1)
				(type default)
			)
			(layer "F.Fab")
		)
		(pad "1" smd rect
			(at -0.2667 0 180)
			(size 0.3048 0.381)
			(layers "F.Cu" "F.Mask" "F.Paste")
			(net "P1V8_CPU1_RT_1D")
		)
		(pad "2" smd rect
			(at 0.2667 0)
			(size 0.3048 0.381)
			(layers "F.Cu" "F.Mask" "F.Paste")
			(net "SMB_RT_CPU1_P0_ROM_MUX_1D_SCL")
		)
	)
	(footprint ""
		(layer "F.Cu")
		(at 149.424644 -373.03583 -90)
		(property "Reference" "C763"
			(at 0 0 270)
			(layer "F.SilkS")
			(hide yes)
			(effects
				(font
					(size 1.27 1.27)
				)
			)
		)
		(property "Value" ""
			(at 0 0 270)
			(layer "F.Fab")
			(effects
				(font
					(size 1.27 1.27)
				)
			)
		)
		(duplicate_pad_numbers_are_jumpers no)
		(fp_line
			(start -0.299974 0.150114)
			(end -0.299974 -0.150114)
			(stroke
				(width 0.1)
				(type default)
			)
			(layer "F.Fab")
		)
		(fp_line
			(start 0.299974 0.150114)
			(end -0.299974 0.150114)
			(stroke
				(width 0.1)
				(type default)
			)
			(layer "F.Fab")
		)
		(fp_line
			(start -0.299974 -0.150114)
			(end 0.299974 -0.150114)
			(stroke
				(width 0.1)
				(type default)
			)
			(layer "F.Fab")
		)
		(fp_line
			(start 0.299974 -0.150114)
			(end 0.299974 0.150114)
			(stroke
				(width 0.1)
				(type default)
			)
			(layer "F.Fab")
		)
		(pad "1" smd rect
			(at -0.2667 0 270)
			(size 0.3048 0.381)
			(layers "F.Cu" "F.Mask" "F.Paste")
			(net "P5E_CPU1_P2_TX_C_DP<5>")
		)
		(pad "2" smd rect
			(at 0.2667 0 270)
			(size 0.3048 0.381)
			(layers "F.Cu" "F.Mask" "F.Paste")
			(net "P5E_CPU1_P2_TX_DP<5>")
		)
	)
	(footprint ""
		(layer "F.Cu")
		(at 171.196 -116.296948)
		(property "Reference" "R51"
			(at 0 0 0)
			(layer "F.SilkS")
			(hide yes)
			(effects
				(font
					(size 1.27 1.27)
				)
			)
		)
		(property "Value" ""
			(at 0 0 0)
			(layer "F.Fab")
			(effects
				(font
					(size 1.27 1.27)
				)
			)
		)
		(duplicate_pad_numbers_are_jumpers no)
		(fp_line
			(start -0.7874 -0.4064)
			(end 0.7874 -0.4064)
			(stroke
				(width 0.1524)
				(type default)
			)
			(layer "F.SilkS")
		)
		(fp_line
			(start -0.7874 0.4064)
			(end -0.7874 -0.4064)
			(stroke
				(width 0.1524)
				(type default)
			)
			(layer "F.SilkS")
		)
		(fp_line
			(start 0.7874 -0.4064)
			(end 0.7874 0.4064)
			(stroke
				(width 0.1524)
				(type default)
			)
			(layer "F.SilkS")
		)
		(fp_line
			(start 0.7874 0.4064)
			(end -0.7874 0.4064)
			(stroke
				(width 0.1524)
				(type default)
			)
			(layer "F.SilkS")
		)
		(fp_line
			(start -0.67945 -0.305054)
			(end -0.12065 -0.305054)
			(stroke
				(width 0.1)
				(type default)
			)
			(layer "F.Fab")
		)
		(fp_line
			(start -0.67945 0.3048)
			(end -0.67945 -0.305054)
			(stroke
				(width 0.1)
				(type default)
			)
			(layer "F.Fab")
		)
		(fp_line
			(start -0.12065 -0.305054)
			(end -0.12065 -0.2794)
			(stroke
				(width 0.1)
				(type default)
			)
			(layer "F.Fab")
		)
		(fp_line
			(start -0.12065 -0.2794)
			(end 0.12065 -0.2794)
			(stroke
				(width 0.1)
				(type default)
			)
			(layer "F.Fab")
		)
		(fp_line
			(start -0.12065 0.2794)
			(end -0.12065 0.3048)
			(stroke
				(width 0.1)
				(type default)
			)
			(layer "F.Fab")
		)
		(fp_line
			(start -0.12065 0.3048)
			(end -0.67945 0.3048)
			(stroke
				(width 0.1)
				(type default)
			)
			(layer "F.Fab")
		)
		(fp_line
			(start 0.120396 0.2794)
			(end -0.12065 0.2794)
			(stroke
				(width 0.1)
				(type default)
			)
			(layer "F.Fab")
		)
		(fp_line
			(start 0.120396 0.3048)
			(end 0.120396 0.2794)
			(stroke
				(width 0.1)
				(type default)
			)
			(layer "F.Fab")
		)
		(fp_line
			(start 0.12065 -0.3048)
			(end 0.67945 -0.3048)
			(stroke
				(width 0.1)
				(type default)
			)
			(layer "F.Fab")
		)
		(fp_line
			(start 0.12065 -0.2794)
			(end 0.12065 -0.3048)
			(stroke
				(width 0.1)
				(type default)
			)
			(layer "F.Fab")
		)
		(fp_line
			(start 0.67945 -0.3048)
			(end 0.67945 0.3048)
			(stroke
				(width 0.1)
				(type default)
			)
			(layer "F.Fab")
		)
		(fp_line
			(start 0.67945 0.3048)
			(end 0.120396 0.3048)
			(stroke
				(width 0.1)
				(type default)
			)
			(layer "F.Fab")
		)
		(pad "1" smd circle
			(at -0.40005 0)
			(size 0 0)
			(layers "F.Cu" "F.Mask" "F.Paste")
			(net "SMB_1_PLD_3V3AUX_SCL_R1")
		)
		(pad "2" smd circle
			(at 0.40005 0)
			(size 0 0)
			(layers "F.Cu" "F.Mask" "F.Paste")
			(net "SMB_1_PLD_3V3AUX_SCL_R2")
		)
	)
	(footprint ""
		(layer "F.Cu")
		(at 204.792834 -343.404952)
		(property "Reference" "C348"
			(at 0 0 0)
			(layer "F.SilkS")
			(hide yes)
			(effects
				(font
					(size 1.27 1.27)
				)
			)
		)
		(property "Value" ""
			(at 0 0 0)
			(layer "F.Fab")
			(effects
				(font
					(size 1.27 1.27)
				)
			)
		)
		(duplicate_pad_numbers_are_jumpers no)
		(fp_line
			(start -0.7874 -0.4064)
			(end 0.7874 -0.4064)
			(stroke
				(width 0.1524)
				(type default)
			)
			(layer "F.SilkS")
		)
		(fp_line
			(start -0.7874 0.4064)
			(end -0.7874 -0.4064)
			(stroke
				(width 0.1524)
				(type default)
			)
			(layer "F.SilkS")
		)
		(fp_line
			(start 0.7874 -0.4064)
			(end 0.7874 0.4064)
			(stroke
				(width 0.1524)
				(type default)
			)
			(layer "F.SilkS")
		)
		(fp_line
			(start 0.7874 0.4064)
			(end -0.7874 0.4064)
			(stroke
				(width 0.1524)
				(type default)
			)
			(layer "F.SilkS")
		)
		(fp_line
			(start -0.67945 -0.305054)
			(end -0.12065 -0.305054)
			(stroke
				(width 0.1)
				(type default)
			)
			(layer "F.Fab")
		)
		(fp_line
			(start -0.67945 0.3048)
			(end -0.67945 -0.305054)
			(stroke
				(width 0.1)
				(type default)
			)
			(layer "F.Fab")
		)
		(fp_line
			(start -0.12065 -0.305054)
			(end -0.12065 -0.2794)
			(stroke
				(width 0.1)
				(type default)
			)
			(layer "F.Fab")
		)
		(fp_line
			(start -0.12065 -0.2794)
			(end 0.12065 -0.2794)
			(stroke
				(width 0.1)
				(type default)
			)
			(layer "F.Fab")
		)
		(fp_line
			(start -0.12065 0.2794)
			(end -0.12065 0.3048)
			(stroke
				(width 0.1)
				(type default)
			)
			(layer "F.Fab")
		)
		(fp_line
			(start -0.12065 0.3048)
			(end -0.67945 0.3048)
			(stroke
				(width 0.1)
				(type default)
			)
			(layer "F.Fab")
		)
		(fp_line
			(start 0.120396 0.2794)
			(end -0.12065 0.2794)
			(stroke
				(width 0.1)
				(type default)
			)
			(layer "F.Fab")
		)
		(fp_line
			(start 0.120396 0.3048)
			(end 0.120396 0.2794)
			(stroke
				(width 0.1)
				(type default)
			)
			(layer "F.Fab")
		)
		(fp_line
			(start 0.12065 -0.3048)
			(end 0.67945 -0.3048)
			(stroke
				(width 0.1)
				(type default)
			)
			(layer "F.Fab")
		)
		(fp_line
			(start 0.12065 -0.2794)
			(end 0.12065 -0.3048)
			(stroke
				(width 0.1)
				(type default)
			)
			(layer "F.Fab")
		)
		(fp_line
			(start 0.67945 -0.3048)
			(end 0.67945 0.3048)
			(stroke
				(width 0.1)
				(type default)
			)
			(layer "F.Fab")
		)
		(fp_line
			(start 0.67945 0.3048)
			(end 0.120396 0.3048)
			(stroke
				(width 0.1)
				(type default)
			)
			(layer "F.Fab")
		)
		(pad "1" smd circle
			(at -0.40005 0)
			(size 0 0)
			(layers "F.Cu" "F.Mask" "F.Paste")
			(net "PVDD33_S5_EN")
		)
		(pad "2" smd circle
			(at 0.40005 0)
			(size 0 0)
			(layers "F.Cu" "F.Mask" "F.Paste")
			(net "GND")
		)
	)
	(footprint ""
		(layer "F.Cu")
		(at 304.419 -355.854)
		(property "Reference" "R61"
			(at 0 0 0)
			(layer "F.SilkS")
			(hide yes)
			(effects
				(font
					(size 1.27 1.27)
				)
			)
		)
		(property "Value" ""
			(at 0 0 0)
			(layer "F.Fab")
			(effects
				(font
					(size 1.27 1.27)
				)
			)
		)
		(duplicate_pad_numbers_are_jumpers no)
		(fp_line
			(start -0.7874 -0.4064)
			(end 0.7874 -0.4064)
			(stroke
				(width 0.1524)
				(type default)
			)
			(layer "F.SilkS")
		)
		(fp_line
			(start -0.7874 0.4064)
			(end -0.7874 -0.4064)
			(stroke
				(width 0.1524)
				(type default)
			)
			(layer "F.SilkS")
		)
		(fp_line
			(start 0.7874 -0.4064)
			(end 0.7874 0.4064)
			(stroke
				(width 0.1524)
				(type default)
			)
			(layer "F.SilkS")
		)
		(fp_line
			(start 0.7874 0.4064)
			(end -0.7874 0.4064)
			(stroke
				(width 0.1524)
				(type default)
			)
			(layer "F.SilkS")
		)
		(fp_line
			(start -0.67945 -0.305054)
			(end -0.12065 -0.305054)
			(stroke
				(width 0.1)
				(type default)
			)
			(layer "F.Fab")
		)
		(fp_line
			(start -0.67945 0.3048)
			(end -0.67945 -0.305054)
			(stroke
				(width 0.1)
				(type default)
			)
			(layer "F.Fab")
		)
		(fp_line
			(start -0.12065 -0.305054)
			(end -0.12065 -0.2794)
			(stroke
				(width 0.1)
				(type default)
			)
			(layer "F.Fab")
		)
		(fp_line
			(start -0.12065 -0.2794)
			(end 0.12065 -0.2794)
			(stroke
				(width 0.1)
				(type default)
			)
			(layer "F.Fab")
		)
		(fp_line
			(start -0.12065 0.2794)
			(end -0.12065 0.3048)
			(stroke
				(width 0.1)
				(type default)
			)
			(layer "F.Fab")
		)
		(fp_line
			(start -0.12065 0.3048)
			(end -0.67945 0.3048)
			(stroke
				(width 0.1)
				(type default)
			)
			(layer "F.Fab")
		)
		(fp_line
			(start 0.120396 0.2794)
			(end -0.12065 0.2794)
			(stroke
				(width 0.1)
				(type default)
			)
			(layer "F.Fab")
		)
		(fp_line
			(start 0.120396 0.3048)
			(end 0.120396 0.2794)
			(stroke
				(width 0.1)
				(type default)
			)
			(layer "F.Fab")
		)
		(fp_line
			(start 0.12065 -0.3048)
			(end 0.67945 -0.3048)
			(stroke
				(width 0.1)
				(type default)
			)
			(layer "F.Fab")
		)
		(fp_line
			(start 0.12065 -0.2794)
			(end 0.12065 -0.3048)
			(stroke
				(width 0.1)
				(type default)
			)
			(layer "F.Fab")
		)
		(fp_line
			(start 0.67945 -0.3048)
			(end 0.67945 0.3048)
			(stroke
				(width 0.1)
				(type default)
			)
			(layer "F.Fab")
		)
		(fp_line
			(start 0.67945 0.3048)
			(end 0.120396 0.3048)
			(stroke
				(width 0.1)
				(type default)
			)
			(layer "F.Fab")
		)
		(pad "1" smd circle
			(at -0.40005 0)
			(size 0 0)
			(layers "F.Cu" "F.Mask" "F.Paste")
			(net "SVID_PVDDCR_CPU1_P0_SVTO")
		)
		(pad "2" smd circle
			(at 0.40005 0)
			(size 0 0)
			(layers "F.Cu" "F.Mask" "F.Paste")
			(net "SVID_PVDDCR_CPU1_P0_SVTO_R")
		)
	)
)
